(kicad_pcb
	(version 20260206)
	(generator "pcbnew")
	(generator_version "10.0")
	(general
		(thickness 1.6)
		(legacy_teardrops no)
	)
	(paper "A4")
	(title_block
		(title "ptb — Lightning_PTB_BRD.brd")
		(comment 1 "Lightning (Wiwynn / Facebook NVMe JBOF) / footprints 51-56 of 61")
	)
	(layers
		(0 "F.Cu" signal "TOP")
		(4 "In1.Cu" signal "L2GND")
		(6 "In2.Cu" signal "L3VCC")
		(2 "B.Cu" signal "BOTTOM")
		(9 "F.Adhes" user "F.Adhesive")
		(11 "B.Adhes" user "B.Adhesive")
		(13 "F.Paste" user "Package Geometry/Pastemask Top")
		(15 "B.Paste" user "Package Geometry/Pastemask Bottom")
		(5 "F.SilkS" user "Ref Des/Silkscreen Top")
		(7 "B.SilkS" user "Ref Des/Silkscreen Bottom")
		(1 "F.Mask" user "Board Geometry/Soldermask Top")
		(3 "B.Mask" user "Board Geometry/Soldermask Bottom")
		(17 "Dwgs.User" user "User.Drawings")
		(19 "Cmts.User" user "User.Comments")
		(21 "Eco1.User" user "User.Eco1")
		(23 "Eco2.User" user "User.Eco2")
		(25 "Edge.Cuts" user "Board Geometry/Outline")
		(27 "Margin" user)
		(31 "F.CrtYd" user "Package Geometry/Place Bound Top")
		(29 "B.CrtYd" user "Package Geometry/Place Bound Bottom")
		(35 "F.Fab" user "Ref Des/Assembly Top")
		(33 "B.Fab" user "Ref Des/Assembly Bottom")
	)
	(footprint ""
		(layer "F.Cu")
		(at 134.375144 -79.273908 180)
		(property "Reference" "Q33"
			(at 0 0 180)
			(layer "F.SilkS")
			(hide yes)
			(effects
				(font
					(size 1.27 1.27)
				)
			)
		)
		(property "Value" "MMBT2222A-3-GP"
			(at 0.10287 -10.29843 180)
			(unlocked yes)
			(layer "F.Fab")
			(hide yes)
			(effects
				(font
					(size 1.016 1.016)
					(thickness 0.1524)
				)
			)
		)
		(property "Device Type" "SOT23CBE2D4H44"
			(at 0.10287 -12.20343 180)
			(unlocked yes)
			(layer "F.Fab")
			(hide yes)
			(effects
				(font
					(size 1.016 1.016)
					(thickness 0.1524)
				)
			)
		)
		(duplicate_pad_numbers_are_jumpers no)
		(fp_line
			(start 1.651 1.778)
			(end 1.651 -1.778)
			(stroke
				(width 0.1524)
				(type default)
			)
			(layer "F.SilkS")
		)
		(fp_line
			(start 1.651 -1.778)
			(end -1.651 -1.778)
			(stroke
				(width 0.1524)
				(type default)
			)
			(layer "F.SilkS")
		)
		(fp_line
			(start -1.651 1.778)
			(end 1.651 1.778)
			(stroke
				(width 0.1524)
				(type default)
			)
			(layer "F.SilkS")
		)
		(fp_line
			(start -1.651 -1.778)
			(end -1.651 1.778)
			(stroke
				(width 0.1524)
				(type default)
			)
			(layer "F.SilkS")
		)
		(fp_poly
			(pts
				(xy -1.778 1.8796) (xy -1.778 -1.8796) (xy 1.778 -1.8796) (xy 1.778 1.8796)
			)
			(stroke
				(width 0)
				(type default)
			)
			(fill no)
			(layer "F.CrtYd")
		)
		(fp_poly
			(pts
				(xy -1.778 1.8796) (xy -1.778 -1.8796) (xy 1.778 -1.8796) (xy 1.778 1.8796)
			)
			(stroke
				(width 0)
				(type default)
			)
			(fill no)
			(layer "F.Fab")
		)
		(pad "B" smd custom
			(at -0.98425 0.9525 180)
			(size 0.1905 0.1905)
			(layers "F.Cu" "F.Mask" "F.Paste")
			(net "TRAY_PRESENT_OUT_NET_B")
			(options
				(clearance outline)
				(anchor circle)
			)
			(primitives
				(gr_poly
					(pts
						(arc
							(start -0.1778 0.5715)
							(mid -0.321484 0.511984)
							(end -0.381 0.3683)
						)
						(arc
							(start -0.381 -0.3683)
							(mid -0.321484 -0.511984)
							(end -0.1778 -0.5715)
						)
						(arc
							(start 0.1778 -0.5715)
							(mid 0.321484 -0.511984)
							(end 0.381 -0.3683)
						)
						(arc
							(start 0.381 0.3683)
							(mid 0.321484 0.511984)
							(end 0.1778 0.5715)
						)
					)
					(width 0)
					(fill yes)
				)
			)
		)
		(pad "C" smd custom
			(at 0 -0.9525 180)
			(size 0.1905 0.1905)
			(layers "F.Cu" "F.Mask" "F.Paste")
			(net "TRAY PRESENT_OUT#_C")
			(options
				(clearance outline)
				(anchor circle)
			)
			(primitives
				(gr_poly
					(pts
						(arc
							(start -0.1778 0.5715)
							(mid -0.321484 0.511984)
							(end -0.381 0.3683)
						)
						(arc
							(start -0.381 -0.3683)
							(mid -0.321484 -0.511984)
							(end -0.1778 -0.5715)
						)
						(arc
							(start 0.1778 -0.5715)
							(mid 0.321484 -0.511984)
							(end 0.381 -0.3683)
						)
						(arc
							(start 0.381 0.3683)
							(mid 0.321484 0.511984)
							(end 0.1778 0.5715)
						)
					)
					(width 0)
					(fill yes)
				)
			)
		)
		(pad "E" smd custom
			(at 0.98425 0.9525 180)
			(size 0.1905 0.1905)
			(layers "F.Cu" "F.Mask" "F.Paste")
			(net "GND")
			(options
				(clearance outline)
				(anchor circle)
			)
			(primitives
				(gr_poly
					(pts
						(arc
							(start -0.1778 0.5715)
							(mid -0.321484 0.511984)
							(end -0.381 0.3683)
						)
						(arc
							(start -0.381 -0.3683)
							(mid -0.321484 -0.511984)
							(end -0.1778 -0.5715)
						)
						(arc
							(start 0.1778 -0.5715)
							(mid 0.321484 -0.511984)
							(end 0.381 -0.3683)
						)
						(arc
							(start 0.381 0.3683)
							(mid 0.321484 0.511984)
							(end 0.1778 0.5715)
						)
					)
					(width 0)
					(fill yes)
				)
			)
		)
	)
	(footprint ""
		(layer "F.Cu")
		(at 12.27455 -89.9541 180)
		(property "Reference" "R343"
			(at 0 0 180)
			(layer "F.SilkS")
			(hide yes)
			(effects
				(font
					(size 1.27 1.27)
				)
			)
		)
		(property "Value" "10KR2F-2-GP"
			(at 0.064008 -3.993896 180)
			(unlocked yes)
			(layer "F.Fab")
			(hide yes)
			(effects
				(font
					(size 1.016 1.016)
					(thickness 0.1524)
				)
			)
		)
		(property "Device Type" "R402H16"
			(at 0.064008 -5.517896 180)
			(unlocked yes)
			(layer "F.Fab")
			(hide yes)
			(effects
				(font
					(size 1.016 1.016)
					(thickness 0.1524)
				)
			)
		)
		(duplicate_pad_numbers_are_jumpers no)
		(fp_line
			(start 0.508 -0.9398)
			(end -0.508 -0.9398)
			(stroke
				(width 0.1524)
				(type default)
			)
			(layer "F.SilkS")
		)
		(fp_line
			(start -0.508 -0.9398)
			(end -0.508 0.9398)
			(stroke
				(width 0.1524)
				(type default)
			)
			(layer "F.SilkS")
		)
		(fp_rect
			(start -0.508 0.9398)
			(end 0.508 -0.9398)
			(stroke
				(width 0)
				(type default)
			)
			(fill no)
			(layer "F.CrtYd")
		)
		(fp_rect
			(start -0.508 0.9398)
			(end 0.508 -0.9398)
			(stroke
				(width 0)
				(type default)
			)
			(fill no)
			(layer "F.Fab")
		)
		(pad "1" smd custom
			(at 0 -0.4445 180)
			(size 0.1397 0.1397)
			(layers "F.Cu" "F.Mask" "F.Paste")
			(net "P3V3")
			(options
				(clearance outline)
				(anchor circle)
			)
			(primitives
				(gr_poly
					(pts
						(arc
							(start -0.1778 -0.2794)
							(mid -0.249642 -0.249642)
							(end -0.2794 -0.1778)
						)
						(arc
							(start -0.2794 0.1778)
							(mid -0.249642 0.249642)
							(end -0.1778 0.2794)
						)
						(arc
							(start 0.1778 0.2794)
							(mid 0.249642 0.249642)
							(end 0.2794 0.1778)
						)
						(arc
							(start 0.2794 -0.1778)
							(mid 0.249642 -0.249642)
							(end 0.1778 -0.2794)
						)
					)
					(width 0)
					(fill yes)
				)
			)
		)
		(pad "2" smd custom
			(at 0 0.4445 180)
			(size 0.1397 0.1397)
			(layers "F.Cu" "F.Mask" "F.Paste")
			(net "I2C_C_BUF_EN")
			(options
				(clearance outline)
				(anchor circle)
			)
			(primitives
				(gr_poly
					(pts
						(arc
							(start -0.1778 -0.2794)
							(mid -0.249642 -0.249642)
							(end -0.2794 -0.1778)
						)
						(arc
							(start -0.2794 0.1778)
							(mid -0.249642 0.249642)
							(end -0.1778 0.2794)
						)
						(arc
							(start 0.1778 0.2794)
							(mid 0.249642 0.249642)
							(end 0.2794 0.1778)
						)
						(arc
							(start 0.2794 -0.1778)
							(mid 0.249642 -0.249642)
							(end 0.1778 -0.2794)
						)
					)
					(width 0)
					(fill yes)
				)
			)
		)
	)
	(footprint ""
		(layer "F.Cu")
		(at 130.299206 -47.183548 180)
		(property "Reference" "TC5"
			(at 0 0 180)
			(layer "F.SilkS")
			(hide yes)
			(effects
				(font
					(size 1.27 1.27)
				)
			)
		)
		(property "Value" "ST68U16VDM-1-GP"
			(at 0 -9.6012 180)
			(unlocked yes)
			(layer "F.Fab")
			(hide yes)
			(effects
				(font
					(size 1.016 1.016)
					(thickness 0.1524)
				)
			)
		)
		(property "Device Type" "CT7343H79"
			(at 0 -11.1252 180)
			(unlocked yes)
			(layer "F.Fab")
			(hide yes)
			(effects
				(font
					(size 1.016 1.016)
					(thickness 0.1524)
				)
			)
		)
		(duplicate_pad_numbers_are_jumpers no)
		(fp_line
			(start 2.286 4.8768)
			(end -2.286 4.8768)
			(stroke
				(width 0.1524)
				(type default)
			)
			(layer "F.SilkS")
		)
		(fp_line
			(start 2.286 2.032)
			(end 2.286 4.8768)
			(stroke
				(width 0.1524)
				(type default)
			)
			(layer "F.SilkS")
		)
		(fp_line
			(start 2.286 -2.032)
			(end 2.286 -4.8768)
			(stroke
				(width 0.1524)
				(type default)
			)
			(layer "F.SilkS")
		)
		(fp_line
			(start 2.286 -4.8768)
			(end -2.286 -4.8768)
			(stroke
				(width 0.1524)
				(type default)
			)
			(layer "F.SilkS")
		)
		(fp_line
			(start 2.1082 -4.699)
			(end -2.1082 -4.699)
			(stroke
				(width 0.508)
				(type default)
			)
			(layer "F.SilkS")
		)
		(fp_line
			(start -2.286 4.8768)
			(end -2.286 2.032)
			(stroke
				(width 0.1524)
				(type default)
			)
			(layer "F.SilkS")
		)
		(fp_line
			(start -2.286 -4.8768)
			(end -2.286 -2.032)
			(stroke
				(width 0.1524)
				(type default)
			)
			(layer "F.SilkS")
		)
		(fp_rect
			(start -2.1463 3.6449)
			(end 2.1463 -3.6449)
			(stroke
				(width 0)
				(type default)
			)
			(fill no)
			(layer "F.CrtYd")
		)
		(fp_poly
			(pts
				(xy -2.54 4.953) (xy -2.54 4.2926) (xy -3.81 4.2926) (xy -3.81 -4.2926) (xy -2.54 -4.2926) (xy -2.54 -4.953)
				(xy 2.54 -4.953) (xy 2.54 -4.2926) (xy 3.81 -4.2926) (xy 3.81 -1.6256) (xy 2.1463 -1.6256) (xy 2.1463 -3.6449)
				(xy -2.1463 -3.6449) (xy -2.1463 3.6449) (xy 2.1463 3.6449) (xy 2.1463 -1.6129) (xy 3.81 -1.6129)
				(xy 3.81 4.2926) (xy 2.54 4.2926) (xy 2.54 4.953)
			)
			(stroke
				(width 0)
				(type default)
			)
			(fill no)
			(layer "F.CrtYd")
		)
		(fp_rect
			(start 2.54 4.2926)
			(end 3.81 -4.2926)
			(stroke
				(width 0)
				(type default)
			)
			(fill no)
			(layer "F.Fab")
		)
		(fp_rect
			(start -2.54 4.953)
			(end 2.54 -4.953)
			(stroke
				(width 0)
				(type default)
			)
			(fill no)
			(layer "F.Fab")
		)
		(fp_rect
			(start -3.81 4.2926)
			(end -2.54 -4.2926)
			(stroke
				(width 0)
				(type default)
			)
			(fill no)
			(layer "F.Fab")
		)
		(pad "1" smd rect
			(at 0 -3.1496 180)
			(size 2.413 2.286)
			(layers "F.Cu" "F.Mask" "F.Paste")
			(net "P12V")
		)
		(pad "2" smd rect
			(at 0 3.1496 180)
			(size 2.413 2.286)
			(layers "F.Cu" "F.Mask" "F.Paste")
			(net "GND")
		)
		(zone
			(layer "F.Cu")
			(hatch none 0.5)
			(connect_pads
				(clearance 0)
			)
			(min_thickness 0.25)
			(keepout
				(tracks allowed)
				(vias not_allowed)
				(pads allowed)
				(copperpour not_allowed)
				(footprints allowed)
			)
			(placement
				(enabled no)
				(sheetname "")
			)
			(fill
				(thermal_gap 0.5)
				(thermal_bridge_width 0.5)
				(island_removal_mode 0)
			)
			(polygon
				(pts
					(xy 128.787906 -45.494448) (xy 128.787906 -42.586148) (xy 131.810506 -42.586148) (xy 131.810506 -45.481748)
					(xy 131.810506 -45.811948) (xy 128.787906 -45.811948)
				)
			)
		)
		(zone
			(layer "F.Cu")
			(hatch none 0.5)
			(connect_pads
				(clearance 0)
			)
			(min_thickness 0.25)
			(keepout
				(tracks allowed)
				(vias not_allowed)
				(pads allowed)
				(copperpour not_allowed)
				(footprints allowed)
			)
			(placement
				(enabled no)
				(sheetname "")
			)
			(fill
				(thermal_gap 0.5)
				(thermal_bridge_width 0.5)
				(island_removal_mode 0)
			)
			(polygon
				(pts
					(xy 131.810506 -51.780948) (xy 128.787906 -51.780948) (xy 128.787906 -48.885348) (xy 128.787906 -48.555148)
					(xy 131.810506 -48.555148) (xy 131.810506 -48.885348)
				)
			)
		)
	)
	(footprint ""
		(layer "F.Cu")
		(at 10.962386 -95.39859)
		(property "Reference" "R486"
			(at 0 0 0)
			(layer "F.SilkS")
			(hide yes)
			(effects
				(font
					(size 1.27 1.27)
				)
			)
		)
		(property "Value" "0R2J-2-GP"
			(at 0.064008 -3.993896 0)
			(unlocked yes)
			(layer "F.Fab")
			(hide yes)
			(effects
				(font
					(size 1.016 1.016)
					(thickness 0.1524)
				)
			)
		)
		(property "Device Type" "R402H16"
			(at 0.064008 -5.517896 0)
			(unlocked yes)
			(layer "F.Fab")
			(hide yes)
			(effects
				(font
					(size 1.016 1.016)
					(thickness 0.1524)
				)
			)
		)
		(duplicate_pad_numbers_are_jumpers no)
		(fp_line
			(start -0.508 -0.9398)
			(end -0.508 0.9398)
			(stroke
				(width 0.1524)
				(type default)
			)
			(layer "F.SilkS")
		)
		(fp_line
			(start 0.508 -0.9398)
			(end -0.508 -0.9398)
			(stroke
				(width 0.1524)
				(type default)
			)
			(layer "F.SilkS")
		)
		(fp_rect
			(start -0.508 0.9398)
			(end 0.508 -0.9398)
			(stroke
				(width 0)
				(type default)
			)
			(fill no)
			(layer "F.CrtYd")
		)
		(fp_rect
			(start -0.508 0.9398)
			(end 0.508 -0.9398)
			(stroke
				(width 0)
				(type default)
			)
			(fill no)
			(layer "F.Fab")
		)
		(pad "1" smd custom
			(at 0 -0.4445)
			(size 0.1397 0.1397)
			(layers "F.Cu" "F.Mask" "F.Paste")
			(net "I2C_C_BUF_SDAOUT")
			(options
				(clearance outline)
				(anchor circle)
			)
			(primitives
				(gr_poly
					(pts
						(arc
							(start -0.1778 -0.2794)
							(mid -0.249642 -0.249642)
							(end -0.2794 -0.1778)
						)
						(arc
							(start -0.2794 0.1778)
							(mid -0.249642 0.249642)
							(end -0.1778 0.2794)
						)
						(arc
							(start 0.1778 0.2794)
							(mid 0.249642 0.249642)
							(end 0.2794 0.1778)
						)
						(arc
							(start 0.2794 -0.1778)
							(mid 0.249642 -0.249642)
							(end 0.1778 -0.2794)
						)
					)
					(width 0)
					(fill yes)
				)
			)
		)
		(pad "2" smd custom
			(at 0 0.4445)
			(size 0.1397 0.1397)
			(layers "F.Cu" "F.Mask" "F.Paste")
			(net "I2C_C_SDA")
			(options
				(clearance outline)
				(anchor circle)
			)
			(primitives
				(gr_poly
					(pts
						(arc
							(start -0.1778 -0.2794)
							(mid -0.249642 -0.249642)
							(end -0.2794 -0.1778)
						)
						(arc
							(start -0.2794 0.1778)
							(mid -0.249642 0.249642)
							(end -0.1778 0.2794)
						)
						(arc
							(start 0.1778 0.2794)
							(mid 0.249642 0.249642)
							(end 0.2794 0.1778)
						)
						(arc
							(start 0.2794 -0.1778)
							(mid 0.249642 -0.249642)
							(end 0.1778 -0.2794)
						)
					)
					(width 0)
					(fill yes)
				)
			)
		)
	)
	(footprint ""
		(layer "F.Cu")
		(at 155.66009 -87.700104 90)
		(property "Reference" "LED16"
			(at 0 0 90)
			(layer "F.SilkS")
			(hide yes)
			(effects
				(font
					(size 1.27 1.27)
				)
			)
		)
		(property "Value" "LED-IR-1-GP"
			(at -3.513074 -0.460502 90)
			(unlocked yes)
			(layer "F.Fab")
			(hide yes)
			(effects
				(font
					(size 1.016 1.016)
					(thickness 0.1524)
				)
			)
		)
		(property "Device Type" "LED3640AKH166"
			(at -3.513074 -1.984502 90)
			(unlocked yes)
			(layer "F.Fab")
			(hide yes)
			(effects
				(font
					(size 1.016 1.016)
					(thickness 0.1524)
				)
			)
		)
		(duplicate_pad_numbers_are_jumpers no)
		(fp_line
			(start 2.0574 -2.6543)
			(end -2.1844 -2.6543)
			(stroke
				(width 0.1524)
				(type default)
			)
			(layer "F.SilkS")
		)
		(fp_line
			(start -2.1844 -2.6543)
			(end -2.1844 2.6543)
			(stroke
				(width 0.1524)
				(type default)
			)
			(layer "F.SilkS")
		)
		(fp_line
			(start 2.0574 2.6543)
			(end 2.0574 -2.6543)
			(stroke
				(width 0.1524)
				(type default)
			)
			(layer "F.SilkS")
		)
		(fp_line
			(start -2.1844 2.6543)
			(end 2.0574 2.6543)
			(stroke
				(width 0.1524)
				(type default)
			)
			(layer "F.SilkS")
		)
		(fp_line
			(start -2.1844 2.8321)
			(end 2.0574 2.8321)
			(stroke
				(width 0.508)
				(type default)
			)
			(layer "F.SilkS")
		)
		(fp_rect
			(start -1.8034 1.9939)
			(end 1.8034 -1.9939)
			(stroke
				(width 0)
				(type default)
			)
			(fill no)
			(layer "F.CrtYd")
		)
		(fp_poly
			(pts
				(xy -2.4384 2.7305) (xy -2.4384 -2.7305) (xy 2.3114 -2.7305) (xy 2.3114 1.98882) (xy 1.8034 1.98882)
				(xy 1.8034 -1.9939) (xy -1.8034 -1.9939) (xy -1.8034 1.9939) (xy 2.3114 1.9939) (xy 2.3114 2.7305)
			)
			(stroke
				(width 0)
				(type default)
			)
			(fill no)
			(layer "F.CrtYd")
		)
		(fp_rect
			(start -2.4384 2.7305)
			(end 2.3114 -2.7305)
			(stroke
				(width 0)
				(type default)
			)
			(fill no)
			(layer "F.Fab")
		)
		(pad "A" smd rect
			(at -0.374904 -1.455674 90)
			(size 3.0988 1.8796)
			(layers "F.Cu" "F.Mask" "F.Paste")
			(net "P3V3")
		)
		(pad "K" smd rect
			(at -0.374904 1.455674 90)
			(size 3.0988 1.8796)
			(layers "F.Cu" "F.Mask" "F.Paste")
			(net "EMITTER_K")
		)
	)
	(footprint ""
		(layer "F.Cu")
		(at 134.368794 -75.439778 180)
		(property "Reference" "Q34"
			(at 0 0 180)
			(layer "F.SilkS")
			(hide yes)
			(effects
				(font
					(size 1.27 1.27)
				)
			)
		)
		(property "Value" "2N7002-11-GP"
			(at 0.127 -8.9662 180)
			(unlocked yes)
			(layer "F.Fab")
			(hide yes)
			(effects
				(font
					(size 1.016 1.016)
					(thickness 0.1524)
				)
			)
		)
		(property "Device Type" "SOT23DGS2D4H44"
			(at 0.127 -10.4902 180)
			(unlocked yes)
			(layer "F.Fab")
			(hide yes)
			(effects
				(font
					(size 1.016 1.016)
					(thickness 0.1524)
				)
			)
		)
		(duplicate_pad_numbers_are_jumpers no)
		(fp_line
			(start 1.651 1.778)
			(end 1.651 -1.778)
			(stroke
				(width 0.1524)
				(type default)
			)
			(layer "F.SilkS")
		)
		(fp_line
			(start 1.651 -1.778)
			(end -1.651 -1.778)
			(stroke
				(width 0.1524)
				(type default)
			)
			(layer "F.SilkS")
		)
		(fp_line
			(start -1.651 1.778)
			(end 1.651 1.778)
			(stroke
				(width 0.1524)
				(type default)
			)
			(layer "F.SilkS")
		)
		(fp_line
			(start -1.651 -1.778)
			(end -1.651 1.778)
			(stroke
				(width 0.1524)
				(type default)
			)
			(layer "F.SilkS")
		)
		(fp_poly
			(pts
				(xy -1.778 1.8796) (xy -1.778 -1.8796) (xy 1.778 -1.8796) (xy 1.778 1.8796)
			)
			(stroke
				(width 0)
				(type default)
			)
			(fill no)
			(layer "F.CrtYd")
		)
		(fp_poly
			(pts
				(xy -1.778 1.8796) (xy -1.778 -1.8796) (xy 1.778 -1.8796) (xy 1.778 1.8796)
			)
			(stroke
				(width 0)
				(type default)
			)
			(fill no)
			(layer "F.Fab")
		)
		(pad "D" smd custom
			(at 0 -0.9525 180)
			(size 0.1905 0.1905)
			(layers "F.Cu" "F.Mask" "F.Paste")
			(net "SELF_TRAY_PRESENT")
			(options
				(clearance outline)
				(anchor circle)
			)
			(primitives
				(gr_poly
					(pts
						(arc
							(start -0.1778 0.5715)
							(mid -0.321484 0.511984)
							(end -0.381 0.3683)
						)
						(arc
							(start -0.381 -0.3683)
							(mid -0.321484 -0.511984)
							(end -0.1778 -0.5715)
						)
						(arc
							(start 0.1778 -0.5715)
							(mid 0.321484 -0.511984)
							(end 0.381 -0.3683)
						)
						(arc
							(start 0.381 0.3683)
							(mid 0.321484 0.511984)
							(end 0.1778 0.5715)
						)
					)
					(width 0)
					(fill yes)
				)
			)
		)
		(pad "G" smd custom
			(at -0.98425 0.9525 180)
			(size 0.1905 0.1905)
			(layers "F.Cu" "F.Mask" "F.Paste")
			(net "TRAY_MOSFET_G")
			(options
				(clearance outline)
				(anchor circle)
			)
			(primitives
				(gr_poly
					(pts
						(arc
							(start -0.1778 0.5715)
							(mid -0.321484 0.511984)
							(end -0.381 0.3683)
						)
						(arc
							(start -0.381 -0.3683)
							(mid -0.321484 -0.511984)
							(end -0.1778 -0.5715)
						)
						(arc
							(start 0.1778 -0.5715)
							(mid 0.321484 -0.511984)
							(end 0.381 -0.3683)
						)
						(arc
							(start 0.381 0.3683)
							(mid 0.321484 0.511984)
							(end 0.1778 0.5715)
						)
					)
					(width 0)
					(fill yes)
				)
			)
		)
		(pad "S" smd custom
			(at 0.98425 0.9525 180)
			(size 0.1905 0.1905)
			(layers "F.Cu" "F.Mask" "F.Paste")
			(net "GND")
			(options
				(clearance outline)
				(anchor circle)
			)
			(primitives
				(gr_poly
					(pts
						(arc
							(start -0.1778 0.5715)
							(mid -0.321484 0.511984)
							(end -0.381 0.3683)
						)
						(arc
							(start -0.381 -0.3683)
							(mid -0.321484 -0.511984)
							(end -0.1778 -0.5715)
						)
						(arc
							(start 0.1778 -0.5715)
							(mid 0.321484 -0.511984)
							(end 0.381 -0.3683)
						)
						(arc
							(start 0.381 0.3683)
							(mid 0.321484 0.511984)
							(end 0.1778 0.5715)
						)
					)
					(width 0)
					(fill yes)
				)
			)
		)
	)
)
